(kicad_pcb
	(version 20260206)
	(generator "pcbnew")
	(generator_version "10.0")
	(general
		(thickness 1.6)
		(legacy_teardrops no)
	)
	(paper "A4")
	(title_block
		(title "baseboard — 13948-1b.1110WZS1818.brd")
		(comment 1 "Honey Badger (Wiwynn) / footprints 1166-1173 of 2523")
	)
	(layers
		(0 "F.Cu" signal "TOP")
		(4 "In1.Cu" signal "L2GND")
		(6 "In2.Cu" signal "L3")
		(8 "In3.Cu" signal "L4VCC")
		(10 "In4.Cu" signal "L5VCC")
		(12 "In5.Cu" signal "L6")
		(14 "In6.Cu" signal "L7GND")
		(2 "B.Cu" signal "BOTTOM")
		(9 "F.Adhes" user "F.Adhesive")
		(11 "B.Adhes" user "B.Adhesive")
		(13 "F.Paste" user "Package Geometry/Pastemask Top")
		(15 "B.Paste" user "Package Geometry/Pastemask Bottom")
		(5 "F.SilkS" user "Ref Des/Silkscreen Top")
		(7 "B.SilkS" user "Ref Des/Silkscreen Bottom")
		(1 "F.Mask" user "Board Geometry/Soldermask Top")
		(3 "B.Mask" user "Board Geometry/Soldermask Bottom")
		(17 "Dwgs.User" user "User.Drawings")
		(19 "Cmts.User" user "User.Comments")
		(21 "Eco1.User" user "User.Eco1")
		(23 "Eco2.User" user "User.Eco2")
		(25 "Edge.Cuts" user "Board Geometry/Outline")
		(27 "Margin" user)
		(31 "F.CrtYd" user "Package Geometry/Place Bound Top")
		(29 "B.CrtYd" user "Package Geometry/Place Bound Bottom")
		(35 "F.Fab" user "Ref Des/Assembly Top")
		(33 "B.Fab" user "Ref Des/Assembly Bottom")
	)
	(footprint ""
		(layer "F.Cu")
		(at 198.247 -224.282)
		(property "Reference" "R1587"
			(at 0 0 0)
			(layer "F.SilkS")
			(hide yes)
			(effects
				(font
					(size 1.27 1.27)
				)
			)
		)
		(property "Value" "0R2J-2-GP"
			(at 0.064008 -3.993896 0)
			(unlocked yes)
			(layer "F.Fab")
			(hide yes)
			(effects
				(font
					(size 1.016 1.016)
					(thickness 0.1524)
				)
			)
		)
		(property "Device Type" "R402H16"
			(at 0.064008 -5.517896 0)
			(unlocked yes)
			(layer "F.Fab")
			(hide yes)
			(effects
				(font
					(size 1.016 1.016)
					(thickness 0.1524)
				)
			)
		)
		(duplicate_pad_numbers_are_jumpers no)
		(fp_line
			(start -0.508 -0.9398)
			(end -0.508 0.9398)
			(stroke
				(width 0.1524)
				(type default)
			)
			(layer "F.SilkS")
		)
		(fp_line
			(start 0.508 -0.9398)
			(end -0.508 -0.9398)
			(stroke
				(width 0.1524)
				(type default)
			)
			(layer "F.SilkS")
		)
		(fp_rect
			(start -0.508 0.9398)
			(end 0.508 -0.9398)
			(stroke
				(width 0)
				(type default)
			)
			(fill no)
			(layer "F.CrtYd")
		)
		(fp_rect
			(start -0.508 0.9398)
			(end 0.508 -0.9398)
			(stroke
				(width 0)
				(type default)
			)
			(fill no)
			(layer "F.Fab")
		)
		(pad "1" smd custom
			(at 0 -0.4445)
			(size 0.1397 0.1397)
			(layers "F.Cu" "F.Mask" "F.Paste")
			(net "SYS_RSTBTN_N")
			(options
				(clearance outline)
				(anchor circle)
			)
			(primitives
				(gr_poly
					(pts
						(arc
							(start -0.1778 -0.2794)
							(mid -0.249642 -0.249642)
							(end -0.2794 -0.1778)
						)
						(arc
							(start -0.2794 0.1778)
							(mid -0.249642 0.249642)
							(end -0.1778 0.2794)
						)
						(arc
							(start 0.1778 0.2794)
							(mid 0.249642 0.249642)
							(end 0.2794 0.1778)
						)
						(arc
							(start 0.2794 -0.1778)
							(mid 0.249642 -0.249642)
							(end 0.1778 -0.2794)
						)
					)
					(width 0)
					(fill yes)
				)
			)
		)
		(pad "2" smd custom
			(at 0 0.4445)
			(size 0.1397 0.1397)
			(layers "F.Cu" "F.Mask" "F.Paste")
			(net "RSTBTN_FP_N")
			(options
				(clearance outline)
				(anchor circle)
			)
			(primitives
				(gr_poly
					(pts
						(arc
							(start -0.1778 -0.2794)
							(mid -0.249642 -0.249642)
							(end -0.2794 -0.1778)
						)
						(arc
							(start -0.2794 0.1778)
							(mid -0.249642 0.249642)
							(end -0.1778 0.2794)
						)
						(arc
							(start 0.1778 0.2794)
							(mid 0.249642 0.249642)
							(end 0.2794 0.1778)
						)
						(arc
							(start 0.2794 -0.1778)
							(mid 0.249642 -0.249642)
							(end 0.1778 -0.2794)
						)
					)
					(width 0)
					(fill yes)
				)
			)
		)
	)
	(footprint ""
		(layer "F.Cu")
		(at 86.49716 -41.91 -90)
		(property "Reference" "SC892"
			(at 0 0 270)
			(layer "F.SilkS")
			(hide yes)
			(effects
				(font
					(size 1.27 1.27)
				)
			)
		)
		(property "Value" "SCD01U10V1KX-GP"
			(at -2.8321 -1.7399 270)
			(unlocked yes)
			(layer "F.Fab")
			(hide yes)
			(effects
				(font
					(size 1.016 1.016)
					(thickness 0.1524)
				)
			)
		)
		(property "Device Type" "C0201H13"
			(at -2.8321 -3.2639 270)
			(unlocked yes)
			(layer "F.Fab")
			(hide yes)
			(effects
				(font
					(size 1.016 1.016)
					(thickness 0.1524)
				)
			)
		)
		(duplicate_pad_numbers_are_jumpers no)
		(fp_rect
			(start -0.2794 0.6477)
			(end 0.2794 -0.6477)
			(stroke
				(width 0)
				(type default)
			)
			(fill no)
			(layer "F.CrtYd")
		)
		(fp_rect
			(start -0.2794 0.6477)
			(end 0.2794 -0.6477)
			(stroke
				(width 0)
				(type default)
			)
			(fill no)
			(layer "F.Fab")
		)
		(pad "1" smd custom
			(at 0 -0.2794 270)
			(size 0.0762 0.0762)
			(layers "F.Cu" "F.Mask" "F.Paste")
			(net "SAS3008_RAID_TX_C_P6")
			(options
				(clearance outline)
				(anchor circle)
			)
			(primitives
				(gr_poly
					(pts
						(arc
							(start 0.1524 -0.127)
							(mid 0.137521 -0.162921)
							(end 0.1016 -0.1778)
						)
						(arc
							(start -0.1016 -0.1778)
							(mid -0.137521 -0.162921)
							(end -0.1524 -0.127)
						)
						(arc
							(start -0.1524 0.127)
							(mid -0.137521 0.162921)
							(end -0.1016 0.1778)
						)
						(arc
							(start 0.1016 0.1778)
							(mid 0.137521 0.162921)
							(end 0.1524 0.127)
						)
					)
					(width 0)
					(fill yes)
				)
			)
		)
		(pad "2" smd custom
			(at 0 0.2794 270)
			(size 0.0762 0.0762)
			(layers "F.Cu" "F.Mask" "F.Paste")
			(net "IOC_RAID_TX_P6")
			(options
				(clearance outline)
				(anchor circle)
			)
			(primitives
				(gr_poly
					(pts
						(arc
							(start 0.1524 -0.127)
							(mid 0.137521 -0.162921)
							(end 0.1016 -0.1778)
						)
						(arc
							(start -0.1016 -0.1778)
							(mid -0.137521 -0.162921)
							(end -0.1524 -0.127)
						)
						(arc
							(start -0.1524 0.127)
							(mid -0.137521 0.162921)
							(end -0.1016 0.1778)
						)
						(arc
							(start 0.1016 0.1778)
							(mid 0.137521 0.162921)
							(end 0.1524 0.127)
						)
					)
					(width 0)
					(fill yes)
				)
			)
		)
	)
	(footprint ""
		(layer "F.Cu")
		(at 35.052 -80.772 180)
		(property "Reference" "R676"
			(at 0 0 180)
			(layer "F.SilkS")
			(hide yes)
			(effects
				(font
					(size 1.27 1.27)
				)
			)
		)
		(property "Value" "1KR2F-3-GP"
			(at 0.064008 -3.993896 180)
			(unlocked yes)
			(layer "F.Fab")
			(hide yes)
			(effects
				(font
					(size 1.016 1.016)
					(thickness 0.1524)
				)
			)
		)
		(property "Device Type" "R402H16"
			(at 0.064008 -5.517896 180)
			(unlocked yes)
			(layer "F.Fab")
			(hide yes)
			(effects
				(font
					(size 1.016 1.016)
					(thickness 0.1524)
				)
			)
		)
		(duplicate_pad_numbers_are_jumpers no)
		(fp_line
			(start 0.508 -0.9398)
			(end -0.508 -0.9398)
			(stroke
				(width 0.1524)
				(type default)
			)
			(layer "F.SilkS")
		)
		(fp_line
			(start -0.508 -0.9398)
			(end -0.508 0.9398)
			(stroke
				(width 0.1524)
				(type default)
			)
			(layer "F.SilkS")
		)
		(fp_rect
			(start -0.508 0.9398)
			(end 0.508 -0.9398)
			(stroke
				(width 0)
				(type default)
			)
			(fill no)
			(layer "F.CrtYd")
		)
		(fp_rect
			(start -0.508 0.9398)
			(end 0.508 -0.9398)
			(stroke
				(width 0)
				(type default)
			)
			(fill no)
			(layer "F.Fab")
		)
		(pad "1" smd custom
			(at 0 -0.4445 180)
			(size 0.1397 0.1397)
			(layers "F.Cu" "F.Mask" "F.Paste")
			(net "INTA_LED_BLUE_B")
			(options
				(clearance outline)
				(anchor circle)
			)
			(primitives
				(gr_poly
					(pts
						(arc
							(start -0.1778 -0.2794)
							(mid -0.249642 -0.249642)
							(end -0.2794 -0.1778)
						)
						(arc
							(start -0.2794 0.1778)
							(mid -0.249642 0.249642)
							(end -0.1778 0.2794)
						)
						(arc
							(start 0.1778 0.2794)
							(mid 0.249642 0.249642)
							(end 0.2794 0.1778)
						)
						(arc
							(start 0.2794 -0.1778)
							(mid 0.249642 -0.249642)
							(end 0.1778 -0.2794)
						)
					)
					(width 0)
					(fill yes)
				)
			)
		)
		(pad "2" smd custom
			(at 0 0.4445 180)
			(size 0.1397 0.1397)
			(layers "F.Cu" "F.Mask" "F.Paste")
			(net "SAS_STATUS_LED17")
			(options
				(clearance outline)
				(anchor circle)
			)
			(primitives
				(gr_poly
					(pts
						(arc
							(start -0.1778 -0.2794)
							(mid -0.249642 -0.249642)
							(end -0.2794 -0.1778)
						)
						(arc
							(start -0.2794 0.1778)
							(mid -0.249642 0.249642)
							(end -0.1778 0.2794)
						)
						(arc
							(start 0.1778 0.2794)
							(mid 0.249642 0.249642)
							(end 0.2794 0.1778)
						)
						(arc
							(start 0.2794 -0.1778)
							(mid 0.249642 -0.249642)
							(end 0.1778 -0.2794)
						)
					)
					(width 0)
					(fill yes)
				)
			)
		)
	)
	(footprint ""
		(layer "F.Cu")
		(at 300.75378 -197.358 90)
		(property "Reference" "C200"
			(at 0 0 90)
			(layer "F.SilkS")
			(hide yes)
			(effects
				(font
					(size 1.27 1.27)
				)
			)
		)
		(property "Value" "SC1U10V3KX-4GP-U"
			(at 0 -2.8194 90)
			(unlocked yes)
			(layer "F.Fab")
			(hide yes)
			(effects
				(font
					(size 1.016 1.016)
					(thickness 0.1524)
				)
			)
		)
		(property "Device Type" "C603H36"
			(at 0 -4.3434 90)
			(unlocked yes)
			(layer "F.Fab")
			(hide yes)
			(effects
				(font
					(size 1.016 1.016)
					(thickness 0.1524)
				)
			)
		)
		(duplicate_pad_numbers_are_jumpers no)
		(fp_line
			(start 0.508 0)
			(end -0.508 0)
			(stroke
				(width 0.2032)
				(type default)
			)
			(layer "F.SilkS")
		)
		(fp_rect
			(start -0.5842 1.3335)
			(end 0.5842 -1.3335)
			(stroke
				(width 0)
				(type default)
			)
			(fill no)
			(layer "F.CrtYd")
		)
		(fp_rect
			(start -0.5842 1.3335)
			(end 0.5842 -1.3335)
			(stroke
				(width 0)
				(type default)
			)
			(fill no)
			(layer "F.Fab")
		)
		(pad "1" smd custom
			(at 0 -0.762 90)
			(size 0.2159 0.2159)
			(layers "F.Cu" "F.Mask" "F.Paste")
			(net "P1V53_STBY")
			(options
				(clearance outline)
				(anchor circle)
			)
			(primitives
				(gr_poly
					(pts
						(arc
							(start -0.3302 -0.4318)
							(mid -0.402042 -0.402042)
							(end -0.4318 -0.3302)
						)
						(arc
							(start -0.4318 0.3302)
							(mid -0.402042 0.402042)
							(end -0.3302 0.4318)
						)
						(arc
							(start 0.3302 0.4318)
							(mid 0.402042 0.402042)
							(end 0.4318 0.3302)
						)
						(arc
							(start 0.4318 -0.3302)
							(mid 0.402042 -0.402042)
							(end 0.3302 -0.4318)
						)
					)
					(width 0)
					(fill yes)
				)
			)
		)
		(pad "2" smd custom
			(at 0 0.762 90)
			(size 0.2159 0.2159)
			(layers "F.Cu" "F.Mask" "F.Paste")
			(net "GND")
			(options
				(clearance outline)
				(anchor circle)
			)
			(primitives
				(gr_poly
					(pts
						(arc
							(start -0.3302 -0.4318)
							(mid -0.402042 -0.402042)
							(end -0.4318 -0.3302)
						)
						(arc
							(start -0.4318 0.3302)
							(mid -0.402042 0.402042)
							(end -0.3302 0.4318)
						)
						(arc
							(start 0.3302 0.4318)
							(mid 0.402042 0.402042)
							(end 0.4318 0.3302)
						)
						(arc
							(start 0.4318 -0.3302)
							(mid 0.402042 -0.402042)
							(end 0.3302 -0.4318)
						)
					)
					(width 0)
					(fill yes)
				)
			)
		)
	)
	(footprint ""
		(layer "F.Cu")
		(at 274.193 -159.385 90)
		(property "Reference" "R235"
			(at 0 0 90)
			(layer "F.SilkS")
			(hide yes)
			(effects
				(font
					(size 1.27 1.27)
				)
			)
		)
		(property "Value" "100KR2F-L1-GP"
			(at 0.064008 -3.993896 90)
			(unlocked yes)
			(layer "F.Fab")
			(hide yes)
			(effects
				(font
					(size 1.016 1.016)
					(thickness 0.1524)
				)
			)
		)
		(property "Device Type" "R402H16"
			(at 0.064008 -5.517896 90)
			(unlocked yes)
			(layer "F.Fab")
			(hide yes)
			(effects
				(font
					(size 1.016 1.016)
					(thickness 0.1524)
				)
			)
		)
		(duplicate_pad_numbers_are_jumpers no)
		(fp_line
			(start 0.508 -0.9398)
			(end -0.508 -0.9398)
			(stroke
				(width 0.1524)
				(type default)
			)
			(layer "F.SilkS")
		)
		(fp_line
			(start -0.508 -0.9398)
			(end -0.508 0.9398)
			(stroke
				(width 0.1524)
				(type default)
			)
			(layer "F.SilkS")
		)
		(fp_rect
			(start -0.508 0.9398)
			(end 0.508 -0.9398)
			(stroke
				(width 0)
				(type default)
			)
			(fill no)
			(layer "F.CrtYd")
		)
		(fp_rect
			(start -0.508 0.9398)
			(end 0.508 -0.9398)
			(stroke
				(width 0)
				(type default)
			)
			(fill no)
			(layer "F.Fab")
		)
		(pad "1" smd custom
			(at 0 -0.4445 90)
			(size 0.1397 0.1397)
			(layers "F.Cu" "F.Mask" "F.Paste")
			(net "GND")
			(options
				(clearance outline)
				(anchor circle)
			)
			(primitives
				(gr_poly
					(pts
						(arc
							(start -0.1778 -0.2794)
							(mid -0.249642 -0.249642)
							(end -0.2794 -0.1778)
						)
						(arc
							(start -0.2794 0.1778)
							(mid -0.249642 0.249642)
							(end -0.1778 0.2794)
						)
						(arc
							(start 0.1778 0.2794)
							(mid 0.249642 0.249642)
							(end 0.2794 0.1778)
						)
						(arc
							(start 0.2794 -0.1778)
							(mid 0.249642 -0.249642)
							(end 0.1778 -0.2794)
						)
					)
					(width 0)
					(fill yes)
				)
			)
		)
		(pad "2" smd custom
			(at 0 0.4445 90)
			(size 0.1397 0.1397)
			(layers "F.Cu" "F.Mask" "F.Paste")
			(net "TP_BMC0_LPC_LAD1")
			(options
				(clearance outline)
				(anchor circle)
			)
			(primitives
				(gr_poly
					(pts
						(arc
							(start -0.1778 -0.2794)
							(mid -0.249642 -0.249642)
							(end -0.2794 -0.1778)
						)
						(arc
							(start -0.2794 0.1778)
							(mid -0.249642 0.249642)
							(end -0.1778 0.2794)
						)
						(arc
							(start 0.1778 0.2794)
							(mid 0.249642 0.249642)
							(end 0.2794 0.1778)
						)
						(arc
							(start 0.2794 -0.1778)
							(mid 0.249642 -0.249642)
							(end 0.1778 -0.2794)
						)
					)
					(width 0)
					(fill yes)
				)
			)
		)
	)
	(footprint ""
		(layer "F.Cu")
		(at 324.358 -179.705 180)
		(property "Reference" "R3098"
			(at 0 0 180)
			(layer "F.SilkS")
			(hide yes)
			(effects
				(font
					(size 1.27 1.27)
				)
			)
		)
		(property "Value" "1KR2F-3-GP"
			(at 0.064008 -3.993896 180)
			(unlocked yes)
			(layer "F.Fab")
			(hide yes)
			(effects
				(font
					(size 1.016 1.016)
					(thickness 0.1524)
				)
			)
		)
		(property "Device Type" "R402H16"
			(at 0.064008 -5.517896 180)
			(unlocked yes)
			(layer "F.Fab")
			(hide yes)
			(effects
				(font
					(size 1.016 1.016)
					(thickness 0.1524)
				)
			)
		)
		(duplicate_pad_numbers_are_jumpers no)
		(fp_line
			(start 0.508 -0.9398)
			(end -0.508 -0.9398)
			(stroke
				(width 0.1524)
				(type default)
			)
			(layer "F.SilkS")
		)
		(fp_line
			(start -0.508 -0.9398)
			(end -0.508 0.9398)
			(stroke
				(width 0.1524)
				(type default)
			)
			(layer "F.SilkS")
		)
		(fp_rect
			(start -0.508 0.9398)
			(end 0.508 -0.9398)
			(stroke
				(width 0)
				(type default)
			)
			(fill no)
			(layer "F.CrtYd")
		)
		(fp_rect
			(start -0.508 0.9398)
			(end 0.508 -0.9398)
			(stroke
				(width 0)
				(type default)
			)
			(fill no)
			(layer "F.Fab")
		)
		(pad "1" smd custom
			(at 0 -0.4445 180)
			(size 0.1397 0.1397)
			(layers "F.Cu" "F.Mask" "F.Paste")
			(net "ADC_P1V5_C")
			(options
				(clearance outline)
				(anchor circle)
			)
			(primitives
				(gr_poly
					(pts
						(arc
							(start -0.1778 -0.2794)
							(mid -0.249642 -0.249642)
							(end -0.2794 -0.1778)
						)
						(arc
							(start -0.2794 0.1778)
							(mid -0.249642 0.249642)
							(end -0.1778 0.2794)
						)
						(arc
							(start 0.1778 0.2794)
							(mid 0.249642 0.249642)
							(end 0.2794 0.1778)
						)
						(arc
							(start 0.2794 -0.1778)
							(mid 0.249642 -0.249642)
							(end 0.1778 -0.2794)
						)
					)
					(width 0)
					(fill yes)
				)
			)
		)
		(pad "2" smd custom
			(at 0 0.4445 180)
			(size 0.1397 0.1397)
			(layers "F.Cu" "F.Mask" "F.Paste")
			(net "GND")
			(options
				(clearance outline)
				(anchor circle)
			)
			(primitives
				(gr_poly
					(pts
						(arc
							(start -0.1778 -0.2794)
							(mid -0.249642 -0.249642)
							(end -0.2794 -0.1778)
						)
						(arc
							(start -0.2794 0.1778)
							(mid -0.249642 0.249642)
							(end -0.1778 0.2794)
						)
						(arc
							(start 0.1778 0.2794)
							(mid 0.249642 0.249642)
							(end 0.2794 0.1778)
						)
						(arc
							(start 0.2794 -0.1778)
							(mid 0.249642 -0.249642)
							(end 0.1778 -0.2794)
						)
					)
					(width 0)
					(fill yes)
				)
			)
		)
	)
	(footprint ""
		(layer "F.Cu")
		(at 184.023 -221.742 -90)
		(property "Reference" "U171"
			(at 0 0 270)
			(layer "F.SilkS")
			(hide yes)
			(effects
				(font
					(size 1.27 1.27)
				)
			)
		)
		(property "Value" "SNLVC1G126DCKR-GP"
			(at -2.3368 -8.6868 270)
			(unlocked yes)
			(layer "F.Fab")
			(hide yes)
			(effects
				(font
					(size 1.016 1.016)
					(thickness 0.1524)
				)
			)
		)
		(property "Device Type" "SC70-5H44"
			(at -2.3114 -10.414 270)
			(unlocked yes)
			(layer "F.Fab")
			(hide yes)
			(effects
				(font
					(size 1.016 1.016)
					(thickness 0.1524)
				)
			)
		)
		(duplicate_pad_numbers_are_jumpers no)
		(fp_line
			(start -1.27 1.7018)
			(end -1.27 -1.7018)
			(stroke
				(width 0.1524)
				(type default)
			)
			(layer "F.SilkS")
		)
		(fp_line
			(start 1.27 1.7018)
			(end -1.27 1.7018)
			(stroke
				(width 0.1524)
				(type default)
			)
			(layer "F.SilkS")
		)
		(fp_line
			(start -1.27 -1.7018)
			(end 1.27 -1.7018)
			(stroke
				(width 0.1524)
				(type default)
			)
			(layer "F.SilkS")
		)
		(fp_line
			(start 1.27 -1.7018)
			(end 1.27 1.7018)
			(stroke
				(width 0.1524)
				(type default)
			)
			(layer "F.SilkS")
		)
		(fp_line
			(start 0.6604 -1.8034)
			(end 1.3843 -1.8034)
			(stroke
				(width 0.3302)
				(type default)
			)
			(layer "F.SilkS")
		)
		(fp_line
			(start 1.3843 -1.8034)
			(end 1.3843 -1.1176)
			(stroke
				(width 0.3302)
				(type default)
			)
			(layer "F.SilkS")
		)
		(fp_rect
			(start -1.524 1.9558)
			(end 1.524 -1.9558)
			(stroke
				(width 0)
				(type default)
			)
			(fill no)
			(layer "F.CrtYd")
		)
		(fp_poly
			(pts
				(xy -1.524 -1.9558) (xy 1.524 -1.9558) (xy 1.524 1.9558) (xy -1.524 1.9558)
			)
			(stroke
				(width 0)
				(type default)
			)
			(fill no)
			(layer "F.Fab")
		)
		(pad "1" smd rect
			(at 0.65024 -0.8255 270)
			(size 0.4064 1.2192)
			(layers "F.Cu" "F.Mask" "F.Paste")
			(net "FM_BMC_READY_N")
		)
		(pad "2" smd rect
			(at 0 -0.8255 270)
			(size 0.4064 1.2192)
			(layers "F.Cu" "F.Mask" "F.Paste")
			(net "PWRBTN_FP_N")
		)
		(pad "3" smd rect
			(at -0.65024 -0.8255 270)
			(size 0.4064 1.2192)
			(layers "F.Cu" "F.Mask" "F.Paste")
			(net "GND")
		)
		(pad "4" smd rect
			(at -0.65024 0.8255 270)
			(size 0.4064 1.2192)
			(layers "F.Cu" "F.Mask" "F.Paste")
			(net "PWRBTN_OUT_N")
		)
		(pad "5" smd rect
			(at 0.65024 0.8255 270)
			(size 0.4064 1.2192)
			(layers "F.Cu" "F.Mask" "F.Paste")
			(net "P3V3_STBY")
		)
	)
	(footprint ""
		(layer "F.Cu")
		(at 158.369 -104.902 90)
		(property "Reference" "SC1210"
			(at 0 0 90)
			(layer "F.SilkS")
			(hide yes)
			(effects
				(font
					(size 1.27 1.27)
				)
			)
		)
		(property "Value" "SC10U6D3V5KX-4GP"
			(at -0.0762 -6.1214 90)
			(unlocked yes)
			(layer "F.Fab")
			(hide yes)
			(effects
				(font
					(size 1.016 1.016)
					(thickness 0.1524)
				)
			)
		)
		(property "Device Type" "C805H58"
			(at -0.0762 -8.1534 90)
			(unlocked yes)
			(layer "F.Fab")
			(hide yes)
			(effects
				(font
					(size 1.016 1.016)
					(thickness 0.1524)
				)
			)
		)
		(duplicate_pad_numbers_are_jumpers no)
		(fp_line
			(start 0.635 0)
			(end -0.635 0)
			(stroke
				(width 0.508)
				(type default)
			)
			(layer "F.SilkS")
		)
		(fp_rect
			(start -0.9652 1.778)
			(end 0.9652 -1.778)
			(stroke
				(width 0)
				(type default)
			)
			(fill no)
			(layer "F.CrtYd")
		)
		(fp_poly
			(pts
				(xy -0.9652 -1.778) (xy 0.9652 -1.778) (xy 0.9652 1.778) (xy -0.9652 1.778)
			)
			(stroke
				(width 0)
				(type default)
			)
			(fill no)
			(layer "F.Fab")
		)
		(pad "1" smd rect
			(at 0 -0.9652 90)
			(size 1.397 1.143)
			(layers "F.Cu" "F.Mask" "F.Paste")
			(net "P0V9_E")
		)
		(pad "2" smd rect
			(at 0 0.9652 90)
			(size 1.397 1.143)
			(layers "F.Cu" "F.Mask" "F.Paste")
			(net "GND")
		)
	)
)
